(kicad_pcb
	(version 20260206)
	(generator "pcbnew")
	(generator_version "10.0")
	(general
		(thickness 1.6)
		(legacy_teardrops no)
	)
	(paper "A4")
	(title_block
		(title "9054_F0T_PDB_BD_GPU_F_V04_1213_1550_OCP.brd")
		(comment 1 "Grand Teton / footprints 40-45 of 608")
	)
	(layers
		(0 "F.Cu" signal "TOP")
		(4 "In1.Cu" signal "GND")
		(6 "In2.Cu" signal "IN1")
		(8 "In3.Cu" signal "GND1")
		(10 "In4.Cu" signal "VCC")
		(12 "In5.Cu" signal "VCC1")
		(14 "In6.Cu" signal "GND2")
		(16 "In7.Cu" signal "IN2")
		(18 "In8.Cu" signal "GND3")
		(2 "B.Cu" signal "BOTTOM")
		(9 "F.Adhes" user "F.Adhesive")
		(11 "B.Adhes" user "B.Adhesive")
		(13 "F.Paste" user "Package Geometry/Pastemask Top")
		(15 "B.Paste" user "Package Geometry/Pastemask Bottom")
		(5 "F.SilkS" user "Ref Des/Silkscreen Top")
		(7 "B.SilkS" user "Ref Des/Silkscreen Bottom")
		(1 "F.Mask" user "Board Geometry/Soldermask Top")
		(3 "B.Mask" user "Board Geometry/Soldermask Bottom")
		(17 "Dwgs.User" user "User.Drawings")
		(19 "Cmts.User" user "User.Comments")
		(21 "Eco1.User" user "User.Eco1")
		(23 "Eco2.User" user "User.Eco2")
		(25 "Edge.Cuts" user "Board Geometry/Outline")
		(27 "Margin" user)
		(31 "F.CrtYd" user "Package Geometry/Place Bound Top")
		(29 "B.CrtYd" user "Package Geometry/Place Bound Bottom")
		(35 "F.Fab" user "Ref Des/Assembly Top")
		(33 "B.Fab" user "Ref Des/Assembly Bottom")
	)
	(footprint ""
		(layer "F.Cu")
		(at 417.90112 -32.766 90)
		(property "Reference" "R5923"
			(at 0 0 90)
			(layer "F.SilkS")
			(hide yes)
			(effects
				(font
					(size 1.27 1.27)
				)
			)
		)
		(property "Value" ""
			(at 0 0 90)
			(layer "F.Fab")
			(effects
				(font
					(size 1.27 1.27)
				)
			)
		)
		(duplicate_pad_numbers_are_jumpers no)
		(fp_line
			(start 0.7874 -0.4064)
			(end 0.7874 0.4064)
			(stroke
				(width 0.1524)
				(type default)
			)
			(layer "F.SilkS")
		)
		(fp_line
			(start -0.7874 -0.4064)
			(end 0.7874 -0.4064)
			(stroke
				(width 0.1524)
				(type default)
			)
			(layer "F.SilkS")
		)
		(fp_line
			(start 0.7874 0.4064)
			(end -0.7874 0.4064)
			(stroke
				(width 0.1524)
				(type default)
			)
			(layer "F.SilkS")
		)
		(fp_line
			(start -0.7874 0.4064)
			(end -0.7874 -0.4064)
			(stroke
				(width 0.1524)
				(type default)
			)
			(layer "F.SilkS")
		)
		(fp_line
			(start -0.12065 -0.305054)
			(end -0.12065 -0.2794)
			(stroke
				(width 0.1)
				(type default)
			)
			(layer "F.Fab")
		)
		(fp_line
			(start -0.67945 -0.305054)
			(end -0.12065 -0.305054)
			(stroke
				(width 0.1)
				(type default)
			)
			(layer "F.Fab")
		)
		(fp_line
			(start 0.67945 -0.3048)
			(end 0.67945 0.3048)
			(stroke
				(width 0.1)
				(type default)
			)
			(layer "F.Fab")
		)
		(fp_line
			(start 0.12065 -0.3048)
			(end 0.67945 -0.3048)
			(stroke
				(width 0.1)
				(type default)
			)
			(layer "F.Fab")
		)
		(fp_line
			(start 0.12065 -0.2794)
			(end 0.12065 -0.3048)
			(stroke
				(width 0.1)
				(type default)
			)
			(layer "F.Fab")
		)
		(fp_line
			(start -0.12065 -0.2794)
			(end 0.12065 -0.2794)
			(stroke
				(width 0.1)
				(type default)
			)
			(layer "F.Fab")
		)
		(fp_line
			(start 0.120396 0.2794)
			(end -0.12065 0.2794)
			(stroke
				(width 0.1)
				(type default)
			)
			(layer "F.Fab")
		)
		(fp_line
			(start -0.12065 0.2794)
			(end -0.12065 0.3048)
			(stroke
				(width 0.1)
				(type default)
			)
			(layer "F.Fab")
		)
		(fp_line
			(start 0.67945 0.3048)
			(end 0.120396 0.3048)
			(stroke
				(width 0.1)
				(type default)
			)
			(layer "F.Fab")
		)
		(fp_line
			(start 0.120396 0.3048)
			(end 0.120396 0.2794)
			(stroke
				(width 0.1)
				(type default)
			)
			(layer "F.Fab")
		)
		(fp_line
			(start -0.12065 0.3048)
			(end -0.67945 0.3048)
			(stroke
				(width 0.1)
				(type default)
			)
			(layer "F.Fab")
		)
		(fp_line
			(start -0.67945 0.3048)
			(end -0.67945 -0.305054)
			(stroke
				(width 0.1)
				(type default)
			)
			(layer "F.Fab")
		)
		(pad "1" smd circle
			(at -0.40005 0 90)
			(size 0 0)
			(layers "F.Cu" "F.Mask" "F.Paste")
			(net "P12V_LED_ISET")
		)
		(pad "2" smd circle
			(at 0.40005 0 90)
			(size 0 0)
			(layers "F.Cu" "F.Mask" "F.Paste")
			(net "GND")
		)
	)
	(footprint ""
		(layer "F.Cu")
		(at 430.276 -38.989 180)
		(property "Reference" "R134"
			(at 0 0 180)
			(layer "F.SilkS")
			(hide yes)
			(effects
				(font
					(size 1.27 1.27)
				)
			)
		)
		(property "Value" ""
			(at 0 0 180)
			(layer "F.Fab")
			(effects
				(font
					(size 1.27 1.27)
				)
			)
		)
		(duplicate_pad_numbers_are_jumpers no)
		(fp_line
			(start 0.7874 0.4064)
			(end -0.7874 0.4064)
			(stroke
				(width 0.1524)
				(type default)
			)
			(layer "F.SilkS")
		)
		(fp_line
			(start 0.7874 -0.4064)
			(end 0.7874 0.4064)
			(stroke
				(width 0.1524)
				(type default)
			)
			(layer "F.SilkS")
		)
		(fp_line
			(start -0.7874 0.4064)
			(end -0.7874 -0.4064)
			(stroke
				(width 0.1524)
				(type default)
			)
			(layer "F.SilkS")
		)
		(fp_line
			(start -0.7874 -0.4064)
			(end 0.7874 -0.4064)
			(stroke
				(width 0.1524)
				(type default)
			)
			(layer "F.SilkS")
		)
		(fp_line
			(start 0.67945 0.3048)
			(end 0.120396 0.3048)
			(stroke
				(width 0.1)
				(type default)
			)
			(layer "F.Fab")
		)
		(fp_line
			(start 0.67945 -0.3048)
			(end 0.67945 0.3048)
			(stroke
				(width 0.1)
				(type default)
			)
			(layer "F.Fab")
		)
		(fp_line
			(start 0.12065 -0.2794)
			(end 0.12065 -0.3048)
			(stroke
				(width 0.1)
				(type default)
			)
			(layer "F.Fab")
		)
		(fp_line
			(start 0.12065 -0.3048)
			(end 0.67945 -0.3048)
			(stroke
				(width 0.1)
				(type default)
			)
			(layer "F.Fab")
		)
		(fp_line
			(start 0.120396 0.3048)
			(end 0.120396 0.2794)
			(stroke
				(width 0.1)
				(type default)
			)
			(layer "F.Fab")
		)
		(fp_line
			(start 0.120396 0.2794)
			(end -0.12065 0.2794)
			(stroke
				(width 0.1)
				(type default)
			)
			(layer "F.Fab")
		)
		(fp_line
			(start -0.12065 0.3048)
			(end -0.67945 0.3048)
			(stroke
				(width 0.1)
				(type default)
			)
			(layer "F.Fab")
		)
		(fp_line
			(start -0.12065 0.2794)
			(end -0.12065 0.3048)
			(stroke
				(width 0.1)
				(type default)
			)
			(layer "F.Fab")
		)
		(fp_line
			(start -0.12065 -0.2794)
			(end 0.12065 -0.2794)
			(stroke
				(width 0.1)
				(type default)
			)
			(layer "F.Fab")
		)
		(fp_line
			(start -0.12065 -0.305054)
			(end -0.12065 -0.2794)
			(stroke
				(width 0.1)
				(type default)
			)
			(layer "F.Fab")
		)
		(fp_line
			(start -0.67945 0.3048)
			(end -0.67945 -0.305054)
			(stroke
				(width 0.1)
				(type default)
			)
			(layer "F.Fab")
		)
		(fp_line
			(start -0.67945 -0.305054)
			(end -0.12065 -0.305054)
			(stroke
				(width 0.1)
				(type default)
			)
			(layer "F.Fab")
		)
		(pad "1" smd circle
			(at -0.40005 0 180)
			(size 0 0)
			(layers "F.Cu" "F.Mask" "F.Paste")
			(net "P3V3_AUX")
		)
		(pad "2" smd circle
			(at 0.40005 0 180)
			(size 0 0)
			(layers "F.Cu" "F.Mask" "F.Paste")
			(net "BOARD_ID_1")
		)
	)
	(footprint ""
		(layer "F.Cu")
		(at 424.942 -26.67 90)
		(property "Reference" "D4"
			(at -3.7084 -2.733548 90)
			(unlocked yes)
			(layer "F.SilkS")
			(effects
				(font
					(size 0.7874 0.5842)
					(thickness 0.1524)
				)
				(justify left)
			)
		)
		(property "Value" ""
			(at 0 0 90)
			(layer "F.Fab")
			(effects
				(font
					(size 1.27 1.27)
				)
			)
		)
		(duplicate_pad_numbers_are_jumpers no)
		(fp_line
			(start 4.240784 -1.970024)
			(end -3.656584 -1.970024)
			(stroke
				(width 0.1524)
				(type default)
			)
			(layer "F.SilkS")
		)
		(fp_line
			(start -3.656584 -1.970024)
			(end -3.656584 1.970024)
			(stroke
				(width 0.1524)
				(type default)
			)
			(layer "F.SilkS")
		)
		(fp_line
			(start 4.240784 1.970024)
			(end 4.240784 -1.970024)
			(stroke
				(width 0.1524)
				(type default)
			)
			(layer "F.SilkS")
		)
		(fp_line
			(start -3.656584 1.970024)
			(end 4.240784 1.970024)
			(stroke
				(width 0.1524)
				(type default)
			)
			(layer "F.SilkS")
		)
		(fp_poly
			(pts
				(xy 3.580384 1.970024) (xy 3.580384 -1.970024) (xy 4.240784 -1.970024) (xy 4.240784 1.970024)
			)
			(stroke
				(width 0)
				(type default)
			)
			(fill yes)
			(layer "F.SilkS")
		)
		(fp_line
			(start 2.3749 -1.970024)
			(end -2.3749 -1.970024)
			(stroke
				(width 0.1)
				(type default)
			)
			(layer "F.Fab")
		)
		(fp_line
			(start -2.3749 -1.970024)
			(end -2.3749 1.970024)
			(stroke
				(width 0.1)
				(type default)
			)
			(layer "F.Fab")
		)
		(fp_line
			(start 2.3749 1.970024)
			(end 2.3749 -1.970024)
			(stroke
				(width 0.1)
				(type default)
			)
			(layer "F.Fab")
		)
		(fp_line
			(start -2.3749 1.970024)
			(end 2.3749 1.970024)
			(stroke
				(width 0.1)
				(type default)
			)
			(layer "F.Fab")
		)
		(fp_text user "-"
			(at 4.1656 -0.23495 90)
			(unlocked yes)
			(layer "F.Fab")
			(effects
				(font
					(size 1.905 1.4224)
					(thickness 0.1524)
				)
				(justify left)
			)
		)
		(fp_text user "+"
			(at -4.9784 -0.23495 90)
			(unlocked yes)
			(layer "F.Fab")
			(effects
				(font
					(size 1.905 1.4224)
					(thickness 0.1524)
				)
				(justify left)
			)
		)
		(pad "A" smd rect
			(at -2.450084 0 90)
			(size 2.159 2.2606)
			(layers "F.Cu" "F.Mask" "F.Paste")
			(net "GND")
		)
		(pad "C" smd rect
			(at 2.450084 0 90)
			(size 2.159 2.2606)
			(layers "F.Cu" "F.Mask" "F.Paste")
			(net "P12V_HPDB")
		)
	)
	(footprint ""
		(layer "F.Cu")
		(at 130.412236 -83.566)
		(property "Reference" "PR6997"
			(at 0 0 0)
			(layer "F.SilkS")
			(hide yes)
			(effects
				(font
					(size 1.27 1.27)
				)
			)
		)
		(property "Value" ""
			(at 0 0 0)
			(layer "F.Fab")
			(effects
				(font
					(size 1.27 1.27)
				)
			)
		)
		(duplicate_pad_numbers_are_jumpers no)
		(fp_line
			(start -0.7874 -0.4064)
			(end 0.7874 -0.4064)
			(stroke
				(width 0.1524)
				(type default)
			)
			(layer "F.SilkS")
		)
		(fp_line
			(start -0.7874 0.4064)
			(end -0.7874 -0.4064)
			(stroke
				(width 0.1524)
				(type default)
			)
			(layer "F.SilkS")
		)
		(fp_line
			(start 0.7874 -0.4064)
			(end 0.7874 0.4064)
			(stroke
				(width 0.1524)
				(type default)
			)
			(layer "F.SilkS")
		)
		(fp_line
			(start 0.7874 0.4064)
			(end -0.7874 0.4064)
			(stroke
				(width 0.1524)
				(type default)
			)
			(layer "F.SilkS")
		)
		(fp_line
			(start -0.67945 -0.305054)
			(end -0.12065 -0.305054)
			(stroke
				(width 0.1)
				(type default)
			)
			(layer "F.Fab")
		)
		(fp_line
			(start -0.67945 0.3048)
			(end -0.67945 -0.305054)
			(stroke
				(width 0.1)
				(type default)
			)
			(layer "F.Fab")
		)
		(fp_line
			(start -0.12065 -0.305054)
			(end -0.12065 -0.2794)
			(stroke
				(width 0.1)
				(type default)
			)
			(layer "F.Fab")
		)
		(fp_line
			(start -0.12065 -0.2794)
			(end 0.12065 -0.2794)
			(stroke
				(width 0.1)
				(type default)
			)
			(layer "F.Fab")
		)
		(fp_line
			(start -0.12065 0.2794)
			(end -0.12065 0.3048)
			(stroke
				(width 0.1)
				(type default)
			)
			(layer "F.Fab")
		)
		(fp_line
			(start -0.12065 0.3048)
			(end -0.67945 0.3048)
			(stroke
				(width 0.1)
				(type default)
			)
			(layer "F.Fab")
		)
		(fp_line
			(start 0.120396 0.2794)
			(end -0.12065 0.2794)
			(stroke
				(width 0.1)
				(type default)
			)
			(layer "F.Fab")
		)
		(fp_line
			(start 0.120396 0.3048)
			(end 0.120396 0.2794)
			(stroke
				(width 0.1)
				(type default)
			)
			(layer "F.Fab")
		)
		(fp_line
			(start 0.12065 -0.3048)
			(end 0.67945 -0.3048)
			(stroke
				(width 0.1)
				(type default)
			)
			(layer "F.Fab")
		)
		(fp_line
			(start 0.12065 -0.2794)
			(end 0.12065 -0.3048)
			(stroke
				(width 0.1)
				(type default)
			)
			(layer "F.Fab")
		)
		(fp_line
			(start 0.67945 -0.3048)
			(end 0.67945 0.3048)
			(stroke
				(width 0.1)
				(type default)
			)
			(layer "F.Fab")
		)
		(fp_line
			(start 0.67945 0.3048)
			(end 0.120396 0.3048)
			(stroke
				(width 0.1)
				(type default)
			)
			(layer "F.Fab")
		)
		(pad "1" smd rect
			(at -0.40005 0 180)
			(size 0.4572 0.508)
			(layers "F.Cu" "F.Mask" "F.Paste")
			(net "P52V_HS2_TEMPN_R")
		)
		(pad "2" smd rect
			(at 0.40005 0 180)
			(size 0.4572 0.508)
			(layers "F.Cu" "F.Mask" "F.Paste")
			(net "GND1_FIELD_SIGNAL")
		)
	)
	(footprint ""
		(layer "F.Cu")
		(at 271.2974 -79.121 180)
		(property "Reference" "PC576"
			(at 0 0 180)
			(layer "F.SilkS")
			(hide yes)
			(effects
				(font
					(size 1.27 1.27)
				)
			)
		)
		(property "Value" ""
			(at 0 0 180)
			(layer "F.Fab")
			(effects
				(font
					(size 1.27 1.27)
				)
			)
		)
		(duplicate_pad_numbers_are_jumpers no)
		(fp_line
			(start 0.7874 0.4064)
			(end -0.7874 0.4064)
			(stroke
				(width 0.1524)
				(type default)
			)
			(layer "F.SilkS")
		)
		(fp_line
			(start 0.7874 -0.4064)
			(end 0.7874 0.4064)
			(stroke
				(width 0.1524)
				(type default)
			)
			(layer "F.SilkS")
		)
		(fp_line
			(start -0.7874 0.4064)
			(end -0.7874 -0.4064)
			(stroke
				(width 0.1524)
				(type default)
			)
			(layer "F.SilkS")
		)
		(fp_line
			(start -0.7874 -0.4064)
			(end 0.7874 -0.4064)
			(stroke
				(width 0.1524)
				(type default)
			)
			(layer "F.SilkS")
		)
		(fp_line
			(start 0.67945 0.3048)
			(end 0.120396 0.3048)
			(stroke
				(width 0.1)
				(type default)
			)
			(layer "F.Fab")
		)
		(fp_line
			(start 0.67945 -0.3048)
			(end 0.67945 0.3048)
			(stroke
				(width 0.1)
				(type default)
			)
			(layer "F.Fab")
		)
		(fp_line
			(start 0.12065 -0.2794)
			(end 0.12065 -0.3048)
			(stroke
				(width 0.1)
				(type default)
			)
			(layer "F.Fab")
		)
		(fp_line
			(start 0.12065 -0.3048)
			(end 0.67945 -0.3048)
			(stroke
				(width 0.1)
				(type default)
			)
			(layer "F.Fab")
		)
		(fp_line
			(start 0.120396 0.3048)
			(end 0.120396 0.2794)
			(stroke
				(width 0.1)
				(type default)
			)
			(layer "F.Fab")
		)
		(fp_line
			(start 0.120396 0.2794)
			(end -0.12065 0.2794)
			(stroke
				(width 0.1)
				(type default)
			)
			(layer "F.Fab")
		)
		(fp_line
			(start -0.12065 0.3048)
			(end -0.67945 0.3048)
			(stroke
				(width 0.1)
				(type default)
			)
			(layer "F.Fab")
		)
		(fp_line
			(start -0.12065 0.2794)
			(end -0.12065 0.3048)
			(stroke
				(width 0.1)
				(type default)
			)
			(layer "F.Fab")
		)
		(fp_line
			(start -0.12065 -0.2794)
			(end 0.12065 -0.2794)
			(stroke
				(width 0.1)
				(type default)
			)
			(layer "F.Fab")
		)
		(fp_line
			(start -0.12065 -0.305054)
			(end -0.12065 -0.2794)
			(stroke
				(width 0.1)
				(type default)
			)
			(layer "F.Fab")
		)
		(fp_line
			(start -0.67945 0.3048)
			(end -0.67945 -0.305054)
			(stroke
				(width 0.1)
				(type default)
			)
			(layer "F.Fab")
		)
		(fp_line
			(start -0.67945 -0.305054)
			(end -0.12065 -0.305054)
			(stroke
				(width 0.1)
				(type default)
			)
			(layer "F.Fab")
		)
		(pad "1" smd circle
			(at -0.40005 0 180)
			(size 0 0)
			(layers "F.Cu" "F.Mask" "F.Paste")
			(net "P52V_HS1_UVLO_EN")
		)
		(pad "2" smd circle
			(at 0.40005 0 180)
			(size 0 0)
			(layers "F.Cu" "F.Mask" "F.Paste")
			(net "GND_FIELD_SIGNAL")
		)
	)
	(footprint ""
		(layer "F.Cu")
		(at 334.631284 -61.6204 -90)
		(property "Reference" "PR475"
			(at 0 0 270)
			(layer "F.SilkS")
			(hide yes)
			(effects
				(font
					(size 1.27 1.27)
				)
			)
		)
		(property "Value" ""
			(at 0 0 270)
			(layer "F.Fab")
			(effects
				(font
					(size 1.27 1.27)
				)
			)
		)
		(duplicate_pad_numbers_are_jumpers no)
		(fp_line
			(start -1.2954 0.5842)
			(end -1.2954 -0.5842)
			(stroke
				(width 0.1524)
				(type default)
			)
			(layer "F.SilkS")
		)
		(fp_line
			(start 1.2954 0.5842)
			(end -1.2954 0.5842)
			(stroke
				(width 0.1524)
				(type default)
			)
			(layer "F.SilkS")
		)
		(fp_line
			(start -1.2954 -0.5842)
			(end 1.2954 -0.5842)
			(stroke
				(width 0.1524)
				(type default)
			)
			(layer "F.SilkS")
		)
		(fp_line
			(start 1.2954 -0.5842)
			(end 1.2954 0.5842)
			(stroke
				(width 0.1524)
				(type default)
			)
			(layer "F.SilkS")
		)
		(fp_line
			(start -0.8636 0.4572)
			(end -0.8636 0.4318)
			(stroke
				(width 0.1)
				(type default)
			)
			(layer "F.Fab")
		)
		(fp_line
			(start 0.8636 0.4572)
			(end -0.8636 0.4572)
			(stroke
				(width 0.1)
				(type default)
			)
			(layer "F.Fab")
		)
		(fp_line
			(start -0.8636 0.4318)
			(end -0.8636 0.4064)
			(stroke
				(width 0.1)
				(type default)
			)
			(layer "F.Fab")
		)
		(fp_line
			(start -1.1938 0.4064)
			(end -1.1938 -0.406654)
			(stroke
				(width 0.1)
				(type default)
			)
			(layer "F.Fab")
		)
		(fp_line
			(start -0.8636 0.4064)
			(end -1.1938 0.4064)
			(stroke
				(width 0.1)
				(type default)
			)
			(layer "F.Fab")
		)
		(fp_line
			(start 0.8636 0.4064)
			(end 0.8636 0.4572)
			(stroke
				(width 0.1)
				(type default)
			)
			(layer "F.Fab")
		)
		(fp_line
			(start 1.1938 0.4064)
			(end 0.8636 0.4064)
			(stroke
				(width 0.1)
				(type default)
			)
			(layer "F.Fab")
		)
		(fp_line
			(start -1.1938 -0.406654)
			(end -0.8636 -0.406654)
			(stroke
				(width 0.1)
				(type default)
			)
			(layer "F.Fab")
		)
		(fp_line
			(start -0.8636 -0.406654)
			(end -0.8636 -0.4572)
			(stroke
				(width 0.1)
				(type default)
			)
			(layer "F.Fab")
		)
		(fp_line
			(start 0.8636 -0.406654)
			(end 1.1938 -0.406654)
			(stroke
				(width 0.1)
				(type default)
			)
			(layer "F.Fab")
		)
		(fp_line
			(start 1.1938 -0.406654)
			(end 1.1938 0.4064)
			(stroke
				(width 0.1)
				(type default)
			)
			(layer "F.Fab")
		)
		(fp_line
			(start -0.8636 -0.4572)
			(end 0.8636 -0.4572)
			(stroke
				(width 0.1)
				(type default)
			)
			(layer "F.Fab")
		)
		(fp_line
			(start 0.8636 -0.4572)
			(end 0.8636 -0.406654)
			(stroke
				(width 0.1)
				(type default)
			)
			(layer "F.Fab")
		)
		(pad "1" smd rect
			(at -0.7366 0 180)
			(size 0.7112 0.8128)
			(layers "F.Cu" "F.Mask" "F.Paste")
			(net "P52V_HS1_GATE1_R")
		)
		(pad "2" smd rect
			(at 0.7366 0 180)
			(size 0.7112 0.8128)
			(layers "F.Cu" "F.Mask" "F.Paste")
			(net "P52V_HS1_GATE2")
		)
	)
)
